# S9S_MB_2U (Grand Teton) — schematic netlist excerpt (pin names and nets, part order shuffled) for the footprints in the layout excerpt that follows; sources: Cadence DE-HDL packaged netlist, KiCad conversion of 03242023_DA0F0TMBIJ0_F0T_Motherboard_J_brd_V01_OCP.brd

R1837  Q_RES_4P_12  0.001 1% CHIP  pkg R2512_4P_H41  page 251
  \1\  = P12V_AUX
  \2\  = P12V_S3_AUX_CPU1_NVDIMM
  \3\  = P12V_AUX_CPU1_DIMM_ISEN_P
  \4\  = P12V_AUX_CPU1_DIMM_ISEN_N

PC1346  Q_CAP  0.1UF 25V 10% X7R  pkg 0402  page 275 : A = GND ; B = PVCCINFAON_CPU0_VREF
R2453  Q_RES  33.2 1% CHIP  pkg 0402LF  page 241 : A = SMB_VR_3V3AUX_SCL_R ; B = SMB_VR_3V3AUX_SCL_R2

(kicad_pcb
	(version 20260206)
	(generator "pcbnew")
	(generator_version "10.0")
	(general
		(thickness 1.6)
		(legacy_teardrops no)
	)
	(paper "A4")
	(title_block
		(title "03242023_DA0F0TMBIJ0_F0T_Motherboard_J_brd_V01_OCP.brd")
		(comment 1 "Grand Teton / footprints 1762-1764 of 6105")
	)
	(layers
		(0 "F.Cu" signal "TOP")
		(4 "In1.Cu" signal "GND")
		(6 "In2.Cu" signal "IN1")
		(8 "In3.Cu" signal "GND1")
		(10 "In4.Cu" signal "IN2")
		(12 "In5.Cu" signal "GND2")
		(14 "In6.Cu" signal "IN3")
		(16 "In7.Cu" signal "GND3")
		(18 "In8.Cu" signal "VCC")
		(20 "In9.Cu" signal "VCC1")
		(22 "In10.Cu" signal "GND4")
		(24 "In11.Cu" signal "IN4")
		(26 "In12.Cu" signal "GND5")
		(28 "In13.Cu" signal "IN5")
		(30 "In14.Cu" signal "GND6")
		(32 "In15.Cu" signal "IN6")
		(34 "In16.Cu" signal "GND7")
		(2 "B.Cu" signal "BOTTOM")
		(9 "F.Adhes" user "F.Adhesive")
		(11 "B.Adhes" user "B.Adhesive")
		(13 "F.Paste" user "Package Geometry/Pastemask Top")
		(15 "B.Paste" user "Package Geometry/Pastemask Bottom")
		(5 "F.SilkS" user "Ref Des/Silkscreen Top")
		(7 "B.SilkS" user "Ref Des/Silkscreen Bottom")
		(1 "F.Mask" user "Board Geometry/Soldermask Top")
		(3 "B.Mask" user "Board Geometry/Soldermask Bottom")
		(17 "Dwgs.User" user "User.Drawings")
		(19 "Cmts.User" user "User.Comments")
		(21 "Eco1.User" user "User.Eco1")
		(23 "Eco2.User" user "User.Eco2")
		(25 "Edge.Cuts" user "Board Geometry/Outline")
		(27 "Margin" user)
		(31 "F.CrtYd" user "Package Geometry/Place Bound Top")
		(29 "B.CrtYd" user "Package Geometry/Place Bound Bottom")
		(35 "F.Fab" user "Ref Des/Assembly Top")
		(33 "B.Fab" user "Ref Des/Assembly Bottom")
	)
	(footprint ""
		(layer "F.Cu")
		(at 34.370518 -122.380502 -90)
		(property "Reference" "R2453"
			(at 0 0 270)
			(layer "F.SilkS")
			(hide yes)
			(effects
				(font
					(size 1.27 1.27)
				)
			)
		)
		(property "Value" ""
			(at 0 0 270)
			(layer "F.Fab")
			(effects
				(font
					(size 1.27 1.27)
				)
			)
		)
		(duplicate_pad_numbers_are_jumpers no)
		(fp_line
			(start -0.7874 0.4064)
			(end -0.7874 -0.4064)
			(stroke
				(width 0.1524)
				(type default)
			)
			(layer "F.SilkS")
		)
		(fp_line
			(start 0.7874 0.4064)
			(end -0.7874 0.4064)
			(stroke
				(width 0.1524)
				(type default)
			)
			(layer "F.SilkS")
		)
		(fp_line
			(start -0.7874 -0.4064)
			(end 0.7874 -0.4064)
			(stroke
				(width 0.1524)
				(type default)
			)
			(layer "F.SilkS")
		)
		(fp_line
			(start 0.7874 -0.4064)
			(end 0.7874 0.4064)
			(stroke
				(width 0.1524)
				(type default)
			)
			(layer "F.SilkS")
		)
		(fp_line
			(start -0.67945 0.3048)
			(end -0.67945 -0.305054)
			(stroke
				(width 0.1)
				(type default)
			)
			(layer "F.Fab")
		)
		(fp_line
			(start -0.12065 0.3048)
			(end -0.67945 0.3048)
			(stroke
				(width 0.1)
				(type default)
			)
			(layer "F.Fab")
		)
		(fp_line
			(start 0.120396 0.3048)
			(end 0.120396 0.2794)
			(stroke
				(width 0.1)
				(type default)
			)
			(layer "F.Fab")
		)
		(fp_line
			(start 0.67945 0.3048)
			(end 0.120396 0.3048)
			(stroke
				(width 0.1)
				(type default)
			)
			(layer "F.Fab")
		)
		(fp_line
			(start -0.12065 0.2794)
			(end -0.12065 0.3048)
			(stroke
				(width 0.1)
				(type default)
			)
			(layer "F.Fab")
		)
		(fp_line
			(start 0.120396 0.2794)
			(end -0.12065 0.2794)
			(stroke
				(width 0.1)
				(type default)
			)
			(layer "F.Fab")
		)
		(fp_line
			(start -0.12065 -0.2794)
			(end 0.12065 -0.2794)
			(stroke
				(width 0.1)
				(type default)
			)
			(layer "F.Fab")
		)
		(fp_line
			(start 0.12065 -0.2794)
			(end 0.12065 -0.3048)
			(stroke
				(width 0.1)
				(type default)
			)
			(layer "F.Fab")
		)
		(fp_line
			(start 0.12065 -0.3048)
			(end 0.67945 -0.3048)
			(stroke
				(width 0.1)
				(type default)
			)
			(layer "F.Fab")
		)
		(fp_line
			(start 0.67945 -0.3048)
			(end 0.67945 0.3048)
			(stroke
				(width 0.1)
				(type default)
			)
			(layer "F.Fab")
		)
		(fp_line
			(start -0.67945 -0.305054)
			(end -0.12065 -0.305054)
			(stroke
				(width 0.1)
				(type default)
			)
			(layer "F.Fab")
		)
		(fp_line
			(start -0.12065 -0.305054)
			(end -0.12065 -0.2794)
			(stroke
				(width 0.1)
				(type default)
			)
			(layer "F.Fab")
		)
		(pad "1" smd circle
			(at -0.40005 0 270)
			(size 0 0)
			(layers "F.Cu" "F.Mask" "F.Paste")
			(net "SMB_VR_3V3AUX_SCL_R")
		)
		(pad "2" smd circle
			(at 0.40005 0 270)
			(size 0 0)
			(layers "F.Cu" "F.Mask" "F.Paste")
			(net "SMB_VR_3V3AUX_SCL_R2")
		)
	)
	(footprint ""
		(layer "F.Cu")
		(at 21.44522 -335.905094 -90)
		(property "Reference" "R1837"
			(at 0 0 270)
			(layer "F.SilkS")
			(hide yes)
			(effects
				(font
					(size 1.27 1.27)
				)
			)
		)
		(property "Value" ""
			(at 0 0 270)
			(layer "F.Fab")
			(effects
				(font
					(size 1.27 1.27)
				)
			)
		)
		(duplicate_pad_numbers_are_jumpers no)
		(fp_line
			(start -4.0386 1.7526)
			(end -4.0386 -1.7526)
			(stroke
				(width 0.1524)
				(type default)
			)
			(layer "F.SilkS")
		)
		(fp_line
			(start 4.0386 1.7526)
			(end -4.0386 1.7526)
			(stroke
				(width 0.1524)
				(type default)
			)
			(layer "F.SilkS")
		)
		(fp_line
			(start -4.0386 -1.7526)
			(end 4.0386 -1.7526)
			(stroke
				(width 0.1524)
				(type default)
			)
			(layer "F.SilkS")
		)
		(fp_line
			(start 4.0386 -1.7526)
			(end 4.0386 1.7526)
			(stroke
				(width 0.1524)
				(type default)
			)
			(layer "F.SilkS")
		)
		(fp_line
			(start -4.0386 1.7526)
			(end -4.0386 -1.7526)
			(stroke
				(width 0.1)
				(type default)
			)
			(layer "F.Fab")
		)
		(fp_line
			(start 4.0386 1.7526)
			(end -4.0386 1.7526)
			(stroke
				(width 0.1)
				(type default)
			)
			(layer "F.Fab")
		)
		(fp_line
			(start -4.0386 -1.7526)
			(end 4.0386 -1.7526)
			(stroke
				(width 0.1)
				(type default)
			)
			(layer "F.Fab")
		)
		(fp_line
			(start 4.0386 -1.7526)
			(end 4.0386 1.7526)
			(stroke
				(width 0.1)
				(type default)
			)
			(layer "F.Fab")
		)
		(pad "1" smd circle
			(at -3.700018 0 180)
			(size 0 0)
			(layers "F.Cu" "F.Mask" "F.Paste")
			(net "P12V_AUX")
		)
		(pad "2" smd circle
			(at 3.700018 0)
			(size 0 0)
			(layers "F.Cu" "F.Mask" "F.Paste")
			(net "P12V_S3_AUX_CPU1_NVDIMM")
		)
		(pad "3" smd rect
			(at -2.70002 0)
			(size 0.4064 1.1176)
			(layers "F.Cu" "F.Mask" "F.Paste")
			(net "P12V_AUX_CPU1_DIMM_ISEN_P")
		)
		(pad "4" smd rect
			(at 2.70002 0)
			(size 0.4064 1.1176)
			(layers "F.Cu" "F.Mask" "F.Paste")
			(net "P12V_AUX_CPU1_DIMM_ISEN_N")
		)
	)
	(footprint ""
		(layer "F.Cu")
		(at 420.591488 -182.290974 180)
		(property "Reference" "PC1346"
			(at 0 0 180)
			(layer "F.SilkS")
			(hide yes)
			(effects
				(font
					(size 1.27 1.27)
				)
			)
		)
		(property "Value" ""
			(at 0 0 180)
			(layer "F.Fab")
			(effects
				(font
					(size 1.27 1.27)
				)
			)
		)
		(duplicate_pad_numbers_are_jumpers no)
		(fp_line
			(start 0.7874 0.4064)
			(end -0.7874 0.4064)
			(stroke
				(width 0.1524)
				(type default)
			)
			(layer "F.SilkS")
		)
		(fp_line
			(start 0.7874 -0.4064)
			(end 0.7874 0.4064)
			(stroke
				(width 0.1524)
				(type default)
			)
			(layer "F.SilkS")
		)
		(fp_line
			(start -0.7874 0.4064)
			(end -0.7874 -0.4064)
			(stroke
				(width 0.1524)
				(type default)
			)
			(layer "F.SilkS")
		)
		(fp_line
			(start -0.7874 -0.4064)
			(end 0.7874 -0.4064)
			(stroke
				(width 0.1524)
				(type default)
			)
			(layer "F.SilkS")
		)
		(fp_line
			(start 0.67945 0.3048)
			(end 0.120396 0.3048)
			(stroke
				(width 0.1)
				(type default)
			)
			(layer "F.Fab")
		)
		(fp_line
			(start 0.67945 -0.3048)
			(end 0.67945 0.3048)
			(stroke
				(width 0.1)
				(type default)
			)
			(layer "F.Fab")
		)
		(fp_line
			(start 0.12065 -0.2794)
			(end 0.12065 -0.3048)
			(stroke
				(width 0.1)
				(type default)
			)
			(layer "F.Fab")
		)
		(fp_line
			(start 0.12065 -0.3048)
			(end 0.67945 -0.3048)
			(stroke
				(width 0.1)
				(type default)
			)
			(layer "F.Fab")
		)
		(fp_line
			(start 0.120396 0.3048)
			(end 0.120396 0.2794)
			(stroke
				(width 0.1)
				(type default)
			)
			(layer "F.Fab")
		)
		(fp_line
			(start 0.120396 0.2794)
			(end -0.12065 0.2794)
			(stroke
				(width 0.1)
				(type default)
			)
			(layer "F.Fab")
		)
		(fp_line
			(start -0.12065 0.3048)
			(end -0.67945 0.3048)
			(stroke
				(width 0.1)
				(type default)
			)
			(layer "F.Fab")
		)
		(fp_line
			(start -0.12065 0.2794)
			(end -0.12065 0.3048)
			(stroke
				(width 0.1)
				(type default)
			)
			(layer "F.Fab")
		)
		(fp_line
			(start -0.12065 -0.2794)
			(end 0.12065 -0.2794)
			(stroke
				(width 0.1)
				(type default)
			)
			(layer "F.Fab")
		)
		(fp_line
			(start -0.12065 -0.305054)
			(end -0.12065 -0.2794)
			(stroke
				(width 0.1)
				(type default)
			)
			(layer "F.Fab")
		)
		(fp_line
			(start -0.67945 0.3048)
			(end -0.67945 -0.305054)
			(stroke
				(width 0.1)
				(type default)
			)
			(layer "F.Fab")
		)
		(fp_line
			(start -0.67945 -0.305054)
			(end -0.12065 -0.305054)
			(stroke
				(width 0.1)
				(type default)
			)
			(layer "F.Fab")
		)
		(pad "1" smd circle
			(at -0.40005 0 180)
			(size 0 0)
			(layers "F.Cu" "F.Mask" "F.Paste")
			(net "GND")
		)
		(pad "2" smd circle
			(at 0.40005 0 180)
			(size 0 0)
			(layers "F.Cu" "F.Mask" "F.Paste")
			(net "PVCCINFAON_CPU0_VREF")
		)
	)
)
